# T6G (Grand Teton) — schematic netlist excerpt (pin names and nets, part order shuffled) for the footprints in the layout excerpt that follows; sources: Cadence DE-HDL packaged netlist, KiCad conversion of 04192023_DAF0TMB3IC0_F0TG_MB_C_brd_V02_OCP.brd

PR360  Q_RES  5.6 1% CHIP  pkg 0402LF  page 198 : A = SW_PVDDCR_SOC_P0_BOOT1 ; B = SW_PVDDCR_SOC_P0_BOOT1_RC
R273  Q_RES  33 5% CHIP  pkg 0402LF  page 81 : A = RST_CPU1_RSMRST_N ; B = FM_CPU1_RSMRST_N

(kicad_pcb
	(version 20260206)
	(generator "pcbnew")
	(generator_version "10.0")
	(general
		(thickness 1.6)
		(legacy_teardrops no)
	)
	(paper "A4")
	(title_block
		(title "04192023_DAF0TMB3IC0_F0TG_MB_C_brd_V02_OCP.brd")
		(comment 1 "Grand Teton / footprints 281-282 of 8354")
	)
	(layers
		(0 "F.Cu" signal "TOP")
		(4 "In1.Cu" signal "GND")
		(6 "In2.Cu" signal "IN1")
		(8 "In3.Cu" signal "GND1")
		(10 "In4.Cu" signal "IN2")
		(12 "In5.Cu" signal "GND2")
		(14 "In6.Cu" signal "IN3")
		(16 "In7.Cu" signal "GND3")
		(18 "In8.Cu" signal "VCC")
		(20 "In9.Cu" signal "VCC1")
		(22 "In10.Cu" signal "GND4")
		(24 "In11.Cu" signal "IN4")
		(26 "In12.Cu" signal "GND5")
		(28 "In13.Cu" signal "IN5")
		(30 "In14.Cu" signal "GND6")
		(32 "In15.Cu" signal "IN6")
		(34 "In16.Cu" signal "GND7")
		(2 "B.Cu" signal "BOTTOM")
		(9 "F.Adhes" user "F.Adhesive")
		(11 "B.Adhes" user "B.Adhesive")
		(13 "F.Paste" user "Package Geometry/Pastemask Top")
		(15 "B.Paste" user "Package Geometry/Pastemask Bottom")
		(5 "F.SilkS" user "Ref Des/Silkscreen Top")
		(7 "B.SilkS" user "Ref Des/Silkscreen Bottom")
		(1 "F.Mask" user "Board Geometry/Soldermask Top")
		(3 "B.Mask" user "Board Geometry/Soldermask Bottom")
		(17 "Dwgs.User" user "User.Drawings")
		(19 "Cmts.User" user "User.Comments")
		(21 "Eco1.User" user "User.Eco1")
		(23 "Eco2.User" user "User.Eco2")
		(25 "Edge.Cuts" user "Board Geometry/Outline")
		(27 "Margin" user)
		(31 "F.CrtYd" user "Package Geometry/Place Bound Top")
		(29 "B.CrtYd" user "Package Geometry/Place Bound Bottom")
		(35 "F.Fab" user "Ref Des/Assembly Top")
		(33 "B.Fab" user "Ref Des/Assembly Bottom")
	)
	(footprint ""
		(layer "F.Cu")
		(at 397.064992 -172.51934 -90)
		(property "Reference" "PR360"
			(at 0 0 270)
			(layer "F.SilkS")
			(hide yes)
			(effects
				(font
					(size 1.27 1.27)
				)
			)
		)
		(property "Value" ""
			(at 0 0 270)
			(layer "F.Fab")
			(effects
				(font
					(size 1.27 1.27)
				)
			)
		)
		(duplicate_pad_numbers_are_jumpers no)
		(fp_line
			(start -0.7874 0.4064)
			(end -0.7874 -0.4064)
			(stroke
				(width 0.1524)
				(type default)
			)
			(layer "F.SilkS")
		)
		(fp_line
			(start 0.7874 0.4064)
			(end -0.7874 0.4064)
			(stroke
				(width 0.1524)
				(type default)
			)
			(layer "F.SilkS")
		)
		(fp_line
			(start -0.7874 -0.4064)
			(end 0.7874 -0.4064)
			(stroke
				(width 0.1524)
				(type default)
			)
			(layer "F.SilkS")
		)
		(fp_line
			(start 0.7874 -0.4064)
			(end 0.7874 0.4064)
			(stroke
				(width 0.1524)
				(type default)
			)
			(layer "F.SilkS")
		)
		(fp_line
			(start -0.67945 0.3048)
			(end -0.67945 -0.305054)
			(stroke
				(width 0.1)
				(type default)
			)
			(layer "F.Fab")
		)
		(fp_line
			(start -0.12065 0.3048)
			(end -0.67945 0.3048)
			(stroke
				(width 0.1)
				(type default)
			)
			(layer "F.Fab")
		)
		(fp_line
			(start 0.120396 0.3048)
			(end 0.120396 0.2794)
			(stroke
				(width 0.1)
				(type default)
			)
			(layer "F.Fab")
		)
		(fp_line
			(start 0.67945 0.3048)
			(end 0.120396 0.3048)
			(stroke
				(width 0.1)
				(type default)
			)
			(layer "F.Fab")
		)
		(fp_line
			(start -0.12065 0.2794)
			(end -0.12065 0.3048)
			(stroke
				(width 0.1)
				(type default)
			)
			(layer "F.Fab")
		)
		(fp_line
			(start 0.120396 0.2794)
			(end -0.12065 0.2794)
			(stroke
				(width 0.1)
				(type default)
			)
			(layer "F.Fab")
		)
		(fp_line
			(start -0.12065 -0.2794)
			(end 0.12065 -0.2794)
			(stroke
				(width 0.1)
				(type default)
			)
			(layer "F.Fab")
		)
		(fp_line
			(start 0.12065 -0.2794)
			(end 0.12065 -0.3048)
			(stroke
				(width 0.1)
				(type default)
			)
			(layer "F.Fab")
		)
		(fp_line
			(start 0.12065 -0.3048)
			(end 0.67945 -0.3048)
			(stroke
				(width 0.1)
				(type default)
			)
			(layer "F.Fab")
		)
		(fp_line
			(start 0.67945 -0.3048)
			(end 0.67945 0.3048)
			(stroke
				(width 0.1)
				(type default)
			)
			(layer "F.Fab")
		)
		(fp_line
			(start -0.67945 -0.305054)
			(end -0.12065 -0.305054)
			(stroke
				(width 0.1)
				(type default)
			)
			(layer "F.Fab")
		)
		(fp_line
			(start -0.12065 -0.305054)
			(end -0.12065 -0.2794)
			(stroke
				(width 0.1)
				(type default)
			)
			(layer "F.Fab")
		)
		(pad "1" smd circle
			(at -0.40005 0 270)
			(size 0 0)
			(layers "F.Cu" "F.Mask" "F.Paste")
			(net "SW_PVDDCR_SOC_P0_BOOT1")
		)
		(pad "2" smd circle
			(at 0.40005 0 270)
			(size 0 0)
			(layers "F.Cu" "F.Mask" "F.Paste")
			(net "SW_PVDDCR_SOC_P0_BOOT1_RC")
		)
	)
	(footprint ""
		(layer "F.Cu")
		(at 179.959 -129.377948 -90)
		(property "Reference" "R273"
			(at 0 0 270)
			(layer "F.SilkS")
			(hide yes)
			(effects
				(font
					(size 1.27 1.27)
				)
			)
		)
		(property "Value" ""
			(at 0 0 270)
			(layer "F.Fab")
			(effects
				(font
					(size 1.27 1.27)
				)
			)
		)
		(duplicate_pad_numbers_are_jumpers no)
		(fp_line
			(start -0.7874 0.4064)
			(end -0.7874 -0.4064)
			(stroke
				(width 0.1524)
				(type default)
			)
			(layer "F.SilkS")
		)
		(fp_line
			(start 0.7874 0.4064)
			(end -0.7874 0.4064)
			(stroke
				(width 0.1524)
				(type default)
			)
			(layer "F.SilkS")
		)
		(fp_line
			(start -0.7874 -0.4064)
			(end 0.7874 -0.4064)
			(stroke
				(width 0.1524)
				(type default)
			)
			(layer "F.SilkS")
		)
		(fp_line
			(start 0.7874 -0.4064)
			(end 0.7874 0.4064)
			(stroke
				(width 0.1524)
				(type default)
			)
			(layer "F.SilkS")
		)
		(fp_line
			(start -0.67945 0.3048)
			(end -0.67945 -0.305054)
			(stroke
				(width 0.1)
				(type default)
			)
			(layer "F.Fab")
		)
		(fp_line
			(start -0.12065 0.3048)
			(end -0.67945 0.3048)
			(stroke
				(width 0.1)
				(type default)
			)
			(layer "F.Fab")
		)
		(fp_line
			(start 0.120396 0.3048)
			(end 0.120396 0.2794)
			(stroke
				(width 0.1)
				(type default)
			)
			(layer "F.Fab")
		)
		(fp_line
			(start 0.67945 0.3048)
			(end 0.120396 0.3048)
			(stroke
				(width 0.1)
				(type default)
			)
			(layer "F.Fab")
		)
		(fp_line
			(start -0.12065 0.2794)
			(end -0.12065 0.3048)
			(stroke
				(width 0.1)
				(type default)
			)
			(layer "F.Fab")
		)
		(fp_line
			(start 0.120396 0.2794)
			(end -0.12065 0.2794)
			(stroke
				(width 0.1)
				(type default)
			)
			(layer "F.Fab")
		)
		(fp_line
			(start -0.12065 -0.2794)
			(end 0.12065 -0.2794)
			(stroke
				(width 0.1)
				(type default)
			)
			(layer "F.Fab")
		)
		(fp_line
			(start 0.12065 -0.2794)
			(end 0.12065 -0.3048)
			(stroke
				(width 0.1)
				(type default)
			)
			(layer "F.Fab")
		)
		(fp_line
			(start 0.12065 -0.3048)
			(end 0.67945 -0.3048)
			(stroke
				(width 0.1)
				(type default)
			)
			(layer "F.Fab")
		)
		(fp_line
			(start 0.67945 -0.3048)
			(end 0.67945 0.3048)
			(stroke
				(width 0.1)
				(type default)
			)
			(layer "F.Fab")
		)
		(fp_line
			(start -0.67945 -0.305054)
			(end -0.12065 -0.305054)
			(stroke
				(width 0.1)
				(type default)
			)
			(layer "F.Fab")
		)
		(fp_line
			(start -0.12065 -0.305054)
			(end -0.12065 -0.2794)
			(stroke
				(width 0.1)
				(type default)
			)
			(layer "F.Fab")
		)
		(pad "1" smd circle
			(at -0.40005 0 270)
			(size 0 0)
			(layers "F.Cu" "F.Mask" "F.Paste")
			(net "RST_CPU1_RSMRST_N")
		)
		(pad "2" smd circle
			(at 0.40005 0 270)
			(size 0 0)
			(layers "F.Cu" "F.Mask" "F.Paste")
			(net "FM_CPU1_RSMRST_N")
		)
	)
)
